(kicad_pcb
	(version 20260206)
	(generator "pcbnew")
	(generator_version "10.0")
	(general
		(thickness 1.6)
		(legacy_teardrops no)
	)
	(paper "A4")
	(title_block
		(title "timecard-production-celestica-r4006 — R4006-B0001-02_R01.brd")
		(comment 1 "Time Appliance Project (Time Card) / footprints 877-880 of 1113")
	)
	(layers
		(0 "F.Cu" signal "TOP")
		(4 "In1.Cu" signal "L02_GND1")
		(6 "In2.Cu" signal "L03_SIG1")
		(8 "In3.Cu" signal "L04_GND2")
		(10 "In4.Cu" signal "L05_VCC1")
		(12 "In5.Cu" signal "L06_VCC2")
		(14 "In6.Cu" signal "L07_GND3")
		(16 "In7.Cu" signal "L08_SIG2")
		(18 "In8.Cu" signal "L09_GND4")
		(2 "B.Cu" signal "BOTTOM")
		(9 "F.Adhes" user "F.Adhesive")
		(11 "B.Adhes" user "B.Adhesive")
		(13 "F.Paste" user "Package Geometry/Pastemask Top")
		(15 "B.Paste" user "Package Geometry/Pastemask Bottom")
		(5 "F.SilkS" user "Ref Des/Silkscreen Top")
		(7 "B.SilkS" user "Ref Des/Silkscreen Bottom")
		(1 "F.Mask" user "Board Geometry/Soldermask Top")
		(3 "B.Mask" user "Board Geometry/Soldermask Bottom")
		(17 "Dwgs.User" user "User.Drawings")
		(19 "Cmts.User" user "User.Comments")
		(21 "Eco1.User" user "User.Eco1")
		(23 "Eco2.User" user "User.Eco2")
		(25 "Edge.Cuts" user "Board Geometry/Outline")
		(27 "Margin" user)
		(31 "F.CrtYd" user "Package Geometry/Place Bound Top")
		(29 "B.CrtYd" user "Package Geometry/Place Bound Bottom")
		(35 "F.Fab" user "Ref Des/Assembly Top")
		(33 "B.Fab" user "Ref Des/Assembly Bottom")
	)
	(footprint ""
		(layer "B.Cu")
		(at 20.0152 -23.6728 -90)
		(property "Reference" "R160"
			(at -3.8862 -0.26543 270)
			(unlocked yes)
			(layer "B.SilkS")
			(effects
				(font
					(size 0.7874 0.5842)
					(thickness 0.1524)
				)
				(justify mirror)
			)
		)
		(property "Value" "VAL*"
			(at -0.02032 2.13233 270)
			(unlocked yes)
			(layer "B.Fab")
			(hide yes)
			(effects
				(font
					(size 0.7874 0.5842)
					(thickness 0.1524)
				)
				(justify mirror)
			)
		)
		(property "Tolerance" "TOL*"
			(at -0.044704 3.05435 270)
			(unlocked yes)
			(layer "Cmts.User")
			(hide yes)
			(effects
				(font
					(size 0.7874 0.5842)
					(thickness 0.1524)
				)
				(justify mirror)
			)
		)
		(property "User Part Number" "PARTNUM*"
			(at -0.02032 4.024884 270)
			(unlocked yes)
			(layer "Cmts.User")
			(hide yes)
			(effects
				(font
					(size 0.7874 0.5842)
					(thickness 0.1524)
				)
				(justify mirror)
			)
		)
		(property "Device Type" "RESISTOR-G155-14701-01,4.7KOHMA"
			(at -0.008382 1.210564 270)
			(unlocked yes)
			(layer "B.Fab")
			(hide yes)
			(effects
				(font
					(size 0.7874 0.5842)
					(thickness 0.1524)
				)
				(justify mirror)
			)
		)
		(duplicate_pad_numbers_are_jumpers no)
		(fp_line
			(start -1.143 0.5588)
			(end -1.143 -0.5588)
			(stroke
				(width 0.1)
				(type default)
			)
			(layer "B.SilkS")
		)
		(fp_line
			(start 1.143 0.5588)
			(end -1.143 0.5588)
			(stroke
				(width 0.1)
				(type default)
			)
			(layer "B.SilkS")
		)
		(fp_line
			(start -1.143 -0.5588)
			(end 1.143 -0.5588)
			(stroke
				(width 0.1)
				(type default)
			)
			(layer "B.SilkS")
		)
		(fp_line
			(start 1.143 -0.5588)
			(end 1.143 0.5588)
			(stroke
				(width 0.1)
				(type default)
			)
			(layer "B.SilkS")
		)
		(fp_rect
			(start 1.143 -0.5588)
			(end -1.143 0.5588)
			(stroke
				(width 0)
				(type default)
			)
			(fill no)
			(layer "B.CrtYd")
		)
		(fp_line
			(start -0.508 0.3048)
			(end -0.508 -0.3048)
			(stroke
				(width 0.1)
				(type default)
			)
			(layer "B.Fab")
		)
		(fp_line
			(start 0.508 0.3048)
			(end -0.508 0.3048)
			(stroke
				(width 0.1)
				(type default)
			)
			(layer "B.Fab")
		)
		(fp_line
			(start -0.508 -0.3048)
			(end 0.508 -0.3048)
			(stroke
				(width 0.1)
				(type default)
			)
			(layer "B.Fab")
		)
		(fp_line
			(start 0.508 -0.3048)
			(end 0.508 0.3048)
			(stroke
				(width 0.1)
				(type default)
			)
			(layer "B.Fab")
		)
		(pad "1" smd rect
			(at 0.5334 0 90)
			(size 0.7112 0.6096)
			(layers "B.Cu" "B.Mask" "B.Paste")
			(net "XP3R3V_FPGA")
		)
		(pad "2" smd rect
			(at -0.5334 0 90)
			(size 0.7112 0.6096)
			(layers "B.Cu" "B.Mask" "B.Paste")
			(net "UNNAMED_5_24LC16BTISTTSSOP8_I_1")
		)
		(zone
			(layer "B.Cu")
			(hatch none 0.5)
			(connect_pads
				(clearance 0)
			)
			(min_thickness 0.25)
			(keepout
				(tracks allowed)
				(vias not_allowed)
				(pads allowed)
				(copperpour not_allowed)
				(footprints allowed)
			)
			(placement
				(enabled no)
				(sheetname "")
			)
			(fill
				(thermal_gap 0.5)
				(thermal_bridge_width 0.5)
				(island_removal_mode 0)
			)
			(polygon
				(pts
					(xy 20.32 -23.5966) (xy 20.32 -23.749) (xy 19.7104 -23.749) (xy 19.7104 -23.5966)
				)
			)
		)
	)
	(footprint ""
		(layer "B.Cu")
		(at 118.847108 -47.323248 -90)
		(property "Reference" "R271"
			(at -1.698752 -1.771142 270)
			(unlocked yes)
			(layer "B.SilkS")
			(effects
				(font
					(size 0.635 0.4064)
					(thickness 0.1524)
				)
				(justify mirror)
			)
		)
		(property "Value" "VAL*"
			(at 0 3.718306 270)
			(unlocked yes)
			(layer "B.Fab")
			(hide yes)
			(effects
				(font
					(size 0.7874 0.5842)
					(thickness 0.127)
				)
				(justify mirror)
			)
		)
		(property "Tolerance" "TOL*"
			(at 0 4.861306 270)
			(unlocked yes)
			(layer "Cmts.User")
			(hide yes)
			(effects
				(font
					(size 0.7874 0.5842)
					(thickness 0.127)
				)
				(justify mirror)
			)
		)
		(property "User Part Number" "PARTNUM*"
			(at 0 2.575306 270)
			(unlocked yes)
			(layer "Cmts.User")
			(hide yes)
			(effects
				(font
					(size 0.7874 0.5842)
					(thickness 0.127)
				)
				(justify mirror)
			)
		)
		(property "Device Type" "RESISTOR-G155-14701-01,4.7KOHMA"
			(at 0 1.432306 270)
			(unlocked yes)
			(layer "B.Fab")
			(hide yes)
			(effects
				(font
					(size 0.7874 0.5842)
					(thickness 0.127)
				)
				(justify mirror)
			)
		)
		(duplicate_pad_numbers_are_jumpers no)
		(fp_line
			(start -0.970026 0.4699)
			(end 0.970026 0.4699)
			(stroke
				(width 0.1)
				(type default)
			)
			(layer "B.SilkS")
		)
		(fp_line
			(start 0.970026 0.4699)
			(end 0.970026 -0.4699)
			(stroke
				(width 0.1)
				(type default)
			)
			(layer "B.SilkS")
		)
		(fp_line
			(start -0.970026 -0.4699)
			(end -0.970026 0.4699)
			(stroke
				(width 0.1)
				(type default)
			)
			(layer "B.SilkS")
		)
		(fp_line
			(start 0.970026 -0.4699)
			(end -0.970026 -0.4699)
			(stroke
				(width 0.1)
				(type default)
			)
			(layer "B.SilkS")
		)
		(fp_poly
			(pts
				(xy 0.970026 0.4699) (xy -0.970026 0.4699) (xy -0.970026 -0.4699) (xy 0.970026 -0.4699)
			)
			(stroke
				(width 0)
				(type default)
			)
			(fill no)
			(layer "B.CrtYd")
		)
		(fp_line
			(start -0.508 0.3048)
			(end 0.508 0.3048)
			(stroke
				(width 0.1)
				(type default)
			)
			(layer "B.Fab")
		)
		(fp_line
			(start 0.508 0.3048)
			(end 0.508 -0.3048)
			(stroke
				(width 0.1)
				(type default)
			)
			(layer "B.Fab")
		)
		(fp_line
			(start -0.508 -0.3048)
			(end -0.508 0.3048)
			(stroke
				(width 0.1)
				(type default)
			)
			(layer "B.Fab")
		)
		(fp_line
			(start 0.508 -0.3048)
			(end -0.508 -0.3048)
			(stroke
				(width 0.1)
				(type default)
			)
			(layer "B.Fab")
		)
		(pad "1" smd circle
			(at 0.500126 0 90)
			(size 0.635 0.635)
			(layers "B.Cu" "B.Mask" "B.Paste")
			(net "SG")
		)
		(pad "2" smd circle
			(at -0.500126 0 90)
			(size 0.635 0.635)
			(layers "B.Cu" "B.Mask" "B.Paste")
			(net "FPGA_IN_GPSTP2_OUT")
		)
	)
	(footprint ""
		(layer "B.Cu")
		(at 47.2186 -87.9602)
		(property "Reference" "U31"
			(at 0.2794 -3.69443 0)
			(unlocked yes)
			(layer "B.SilkS")
			(effects
				(font
					(size 0.7874 0.5842)
					(thickness 0.1524)
				)
				(justify mirror)
			)
		)
		(property "Value" ""
			(at 0 0 0)
			(layer "B.Fab")
			(effects
				(font
					(size 1.27 1.27)
				)
				(justify mirror)
			)
		)
		(property "User Part Number" "PARTNUM*"
			(at 0.0508 4.52247 0)
			(unlocked yes)
			(layer "Cmts.User")
			(hide yes)
			(effects
				(font
					(size 0.7874 0.5842)
					(thickness 0.1524)
				)
				(justify mirror)
			)
		)
		(property "Device Type" "CAT93C46VI_GT3_SOIC8-G221-1007A"
			(at 0.0254 3.50647 0)
			(unlocked yes)
			(layer "B.Fab")
			(hide yes)
			(effects
				(font
					(size 0.7874 0.5842)
					(thickness 0.1524)
				)
				(justify mirror)
			)
		)
		(duplicate_pad_numbers_are_jumpers no)
		(fp_line
			(start -3.8862 -2.413)
			(end -3.8862 2.413)
			(stroke
				(width 0.1)
				(type default)
			)
			(layer "B.SilkS")
		)
		(fp_line
			(start -3.8862 2.413)
			(end -2.2098 2.413)
			(stroke
				(width 0.1)
				(type default)
			)
			(layer "B.SilkS")
		)
		(fp_line
			(start -2.2098 -2.7051)
			(end -2.2098 -2.413)
			(stroke
				(width 0.1)
				(type default)
			)
			(layer "B.SilkS")
		)
		(fp_line
			(start -2.2098 -2.413)
			(end -3.8862 -2.413)
			(stroke
				(width 0.1)
				(type default)
			)
			(layer "B.SilkS")
		)
		(fp_line
			(start -2.2098 2.413)
			(end -2.2098 2.7051)
			(stroke
				(width 0.1)
				(type default)
			)
			(layer "B.SilkS")
		)
		(fp_line
			(start -2.2098 2.7051)
			(end 2.2098 2.7051)
			(stroke
				(width 0.1)
				(type default)
			)
			(layer "B.SilkS")
		)
		(fp_line
			(start 2.2098 -2.7051)
			(end -2.2098 -2.7051)
			(stroke
				(width 0.1)
				(type default)
			)
			(layer "B.SilkS")
		)
		(fp_line
			(start 2.2098 -2.413)
			(end 2.2098 -2.7051)
			(stroke
				(width 0.1)
				(type default)
			)
			(layer "B.SilkS")
		)
		(fp_line
			(start 2.2098 2.413)
			(end 3.8862 2.413)
			(stroke
				(width 0.1)
				(type default)
			)
			(layer "B.SilkS")
		)
		(fp_line
			(start 2.2098 2.7051)
			(end 2.2098 2.413)
			(stroke
				(width 0.1)
				(type default)
			)
			(layer "B.SilkS")
		)
		(fp_line
			(start 3.8862 -2.413)
			(end 2.2098 -2.413)
			(stroke
				(width 0.1)
				(type default)
			)
			(layer "B.SilkS")
		)
		(fp_line
			(start 3.8862 2.413)
			(end 3.8862 -2.413)
			(stroke
				(width 0.1)
				(type default)
			)
			(layer "B.SilkS")
		)
		(fp_poly
			(pts
				(arc
					(start 4.9784 -2.9718)
					(mid 4.2164 -2.9718)
					(end 4.9784 -2.9718)
				)
			)
			(stroke
				(width 0)
				(type default)
			)
			(fill yes)
			(layer "B.SilkS")
		)
		(fp_poly
			(pts
				(xy -4.1402 2.9591) (xy -4.1402 -2.9591) (xy 4.1402 -2.9591) (xy 4.1402 2.9591)
			)
			(stroke
				(width 0)
				(type default)
			)
			(fill no)
			(layer "B.CrtYd")
		)
		(fp_line
			(start -2.9972 -2.1082)
			(end -2.9972 -1.7018)
			(stroke
				(width 0.1)
				(type default)
			)
			(layer "B.Fab")
		)
		(fp_line
			(start -2.9972 -1.7018)
			(end -1.9558 -1.7018)
			(stroke
				(width 0.1)
				(type default)
			)
			(layer "B.Fab")
		)
		(fp_line
			(start -2.9972 -0.8382)
			(end -2.9972 -0.4318)
			(stroke
				(width 0.1)
				(type default)
			)
			(layer "B.Fab")
		)
		(fp_line
			(start -2.9972 -0.4318)
			(end -1.9558 -0.4318)
			(stroke
				(width 0.1)
				(type default)
			)
			(layer "B.Fab")
		)
		(fp_line
			(start -2.9972 0.4318)
			(end -2.9972 0.8382)
			(stroke
				(width 0.1)
				(type default)
			)
			(layer "B.Fab")
		)
		(fp_line
			(start -2.9972 0.8382)
			(end -1.9558 0.8382)
			(stroke
				(width 0.1)
				(type default)
			)
			(layer "B.Fab")
		)
		(fp_line
			(start -2.9972 1.7018)
			(end -2.9972 2.1082)
			(stroke
				(width 0.1)
				(type default)
			)
			(layer "B.Fab")
		)
		(fp_line
			(start -2.9972 2.1082)
			(end -1.9558 2.1082)
			(stroke
				(width 0.1)
				(type default)
			)
			(layer "B.Fab")
		)
		(fp_line
			(start -1.9558 -2.4511)
			(end -1.9558 2.4511)
			(stroke
				(width 0.1)
				(type default)
			)
			(layer "B.Fab")
		)
		(fp_line
			(start -1.9558 -2.1082)
			(end -2.9972 -2.1082)
			(stroke
				(width 0.1)
				(type default)
			)
			(layer "B.Fab")
		)
		(fp_line
			(start -1.9558 -0.8382)
			(end -2.9972 -0.8382)
			(stroke
				(width 0.1)
				(type default)
			)
			(layer "B.Fab")
		)
		(fp_line
			(start -1.9558 0.4318)
			(end -2.9972 0.4318)
			(stroke
				(width 0.1)
				(type default)
			)
			(layer "B.Fab")
		)
		(fp_line
			(start -1.9558 1.7018)
			(end -2.9972 1.7018)
			(stroke
				(width 0.1)
				(type default)
			)
			(layer "B.Fab")
		)
		(fp_line
			(start -1.9558 2.4511)
			(end 1.9558 2.4511)
			(stroke
				(width 0.1)
				(type default)
			)
			(layer "B.Fab")
		)
		(fp_line
			(start 1.9558 -2.4511)
			(end -1.9558 -2.4511)
			(stroke
				(width 0.1)
				(type default)
			)
			(layer "B.Fab")
		)
		(fp_line
			(start 1.9558 -2.1082)
			(end 2.9972 -2.1082)
			(stroke
				(width 0.1)
				(type default)
			)
			(layer "B.Fab")
		)
		(fp_line
			(start 1.9558 -0.8382)
			(end 2.9972 -0.8382)
			(stroke
				(width 0.1)
				(type default)
			)
			(layer "B.Fab")
		)
		(fp_line
			(start 1.9558 0.4318)
			(end 2.9972 0.4318)
			(stroke
				(width 0.1)
				(type default)
			)
			(layer "B.Fab")
		)
		(fp_line
			(start 1.9558 1.7018)
			(end 2.9972 1.7018)
			(stroke
				(width 0.1)
				(type default)
			)
			(layer "B.Fab")
		)
		(fp_line
			(start 1.9558 2.4511)
			(end 1.9558 -2.4511)
			(stroke
				(width 0.1)
				(type default)
			)
			(layer "B.Fab")
		)
		(fp_line
			(start 2.9972 -2.1082)
			(end 2.9972 -1.7018)
			(stroke
				(width 0.1)
				(type default)
			)
			(layer "B.Fab")
		)
		(fp_line
			(start 2.9972 -1.7018)
			(end 1.9558 -1.7018)
			(stroke
				(width 0.1)
				(type default)
			)
			(layer "B.Fab")
		)
		(fp_line
			(start 2.9972 -0.8382)
			(end 2.9972 -0.4318)
			(stroke
				(width 0.1)
				(type default)
			)
			(layer "B.Fab")
		)
		(fp_line
			(start 2.9972 -0.4318)
			(end 1.9558 -0.4318)
			(stroke
				(width 0.1)
				(type default)
			)
			(layer "B.Fab")
		)
		(fp_line
			(start 2.9972 0.4318)
			(end 2.9972 0.8382)
			(stroke
				(width 0.1)
				(type default)
			)
			(layer "B.Fab")
		)
		(fp_line
			(start 2.9972 0.8382)
			(end 1.9558 0.8382)
			(stroke
				(width 0.1)
				(type default)
			)
			(layer "B.Fab")
		)
		(fp_line
			(start 2.9972 1.7018)
			(end 2.9972 2.1082)
			(stroke
				(width 0.1)
				(type default)
			)
			(layer "B.Fab")
		)
		(fp_line
			(start 2.9972 2.1082)
			(end 1.9558 2.1082)
			(stroke
				(width 0.1)
				(type default)
			)
			(layer "B.Fab")
		)
		(fp_poly
			(pts
				(arc
					(start 1.284478 -1.899158)
					(mid 0.522478 -1.899158)
					(end 1.284478 -1.899158)
				)
			)
			(stroke
				(width 0)
				(type default)
			)
			(fill yes)
			(layer "B.Fab")
		)
		(fp_text user "8"
			(at -4.4196 -2.04343 0)
			(unlocked yes)
			(layer "B.SilkS")
			(effects
				(font
					(size 0.7874 0.5842)
					(thickness 0.1524)
				)
				(justify mirror)
			)
		)
		(fp_text user "5"
			(at -4.4196 2.90957 0)
			(unlocked yes)
			(layer "B.SilkS")
			(effects
				(font
					(size 0.7874 0.5842)
					(thickness 0.1524)
				)
				(justify mirror)
			)
		)
		(fp_text user "4"
			(at 4.4704 2.78257 0)
			(unlocked yes)
			(layer "B.SilkS")
			(effects
				(font
					(size 0.7874 0.5842)
					(thickness 0.1524)
				)
				(justify mirror)
			)
		)
		(fp_text user "5"
			(at -4.3942 1.93167 0)
			(unlocked yes)
			(layer "B.Fab")
			(effects
				(font
					(size 0.7874 0.5842)
					(thickness 0.1524)
				)
				(justify mirror)
			)
		)
		(fp_text user "8"
			(at -4.3688 -1.87833 0)
			(unlocked yes)
			(layer "B.Fab")
			(effects
				(font
					(size 0.7874 0.5842)
					(thickness 0.1524)
				)
				(justify mirror)
			)
		)
		(fp_text user "4"
			(at 4.3942 2.03327 0)
			(unlocked yes)
			(layer "B.Fab")
			(effects
				(font
					(size 0.7874 0.5842)
					(thickness 0.1524)
				)
				(justify mirror)
			)
		)
		(pad "1" smd rect
			(at 2.8067 -1.905 90)
			(size 0.508 1.651)
			(layers "B.Cu" "B.Mask" "B.Paste")
			(net "FTDI_EE_CS")
		)
		(pad "2" smd rect
			(at 2.8067 -0.635 90)
			(size 0.508 1.651)
			(layers "B.Cu" "B.Mask" "B.Paste")
			(net "FTDI_EE_CLK")
		)
		(pad "3" smd rect
			(at 2.8067 0.635 90)
			(size 0.508 1.651)
			(layers "B.Cu" "B.Mask" "B.Paste")
			(net "FTDI_EE_DAT")
		)
		(pad "4" smd rect
			(at 2.8067 1.905 90)
			(size 0.508 1.651)
			(layers "B.Cu" "B.Mask" "B.Paste")
			(net "FTDI_EE_DO")
		)
		(pad "5" smd rect
			(at -2.8067 1.905 90)
			(size 0.508 1.651)
			(layers "B.Cu" "B.Mask" "B.Paste")
			(net "SG")
		)
		(pad "6" smd rect
			(at -2.8067 0.635 90)
			(size 0.508 1.651)
			(layers "B.Cu" "B.Mask" "B.Paste")
			(net "XP3R3V_FT4232")
		)
		(pad "7" smd rect
			(at -2.8067 -0.635 90)
			(size 0.508 1.651)
			(layers "B.Cu" "B.Mask" "B.Paste")
			(net "Net_296")
		)
		(pad "8" smd rect
			(at -2.8067 -1.905 90)
			(size 0.508 1.651)
			(layers "B.Cu" "B.Mask" "B.Paste")
			(net "XP3R3V_FT4232")
		)
	)
	(footprint ""
		(layer "B.Cu")
		(at 75.184 -73.152 -90)
		(property "Reference" "C58"
			(at -3.429 -0.34163 270)
			(unlocked yes)
			(layer "B.SilkS")
			(effects
				(font
					(size 0.7874 0.5842)
					(thickness 0.1524)
				)
				(justify mirror)
			)
		)
		(property "Value" "VAL*"
			(at -0.0762 3.134106 270)
			(unlocked yes)
			(layer "B.Fab")
			(hide yes)
			(effects
				(font
					(size 0.7874 0.5842)
					(thickness 0.1524)
				)
				(justify mirror)
			)
		)
		(property "Device Type" "CAPACITOR-G107-0F106-EM,10UF,2A"
			(at -0.0508 2.194306 270)
			(unlocked yes)
			(layer "B.Fab")
			(hide yes)
			(effects
				(font
					(size 0.7874 0.5842)
					(thickness 0.1524)
				)
				(justify mirror)
			)
		)
		(property "User Part Number" "PARTNUM*"
			(at -0.1016 5.013706 270)
			(unlocked yes)
			(layer "Cmts.User")
			(hide yes)
			(effects
				(font
					(size 0.7874 0.5842)
					(thickness 0.1524)
				)
				(justify mirror)
			)
		)
		(property "Tolerance" "TOL*"
			(at -0.0762 4.048506 270)
			(unlocked yes)
			(layer "Cmts.User")
			(hide yes)
			(effects
				(font
					(size 0.7874 0.5842)
					(thickness 0.1524)
				)
				(justify mirror)
			)
		)
		(duplicate_pad_numbers_are_jumpers no)
		(fp_line
			(start -1.5748 0.9398)
			(end -1.5748 -0.9398)
			(stroke
				(width 0.1)
				(type default)
			)
			(layer "B.SilkS")
		)
		(fp_line
			(start 1.5748 0.9398)
			(end -1.5748 0.9398)
			(stroke
				(width 0.1)
				(type default)
			)
			(layer "B.SilkS")
		)
		(fp_line
			(start -1.5748 -0.9398)
			(end 1.5748 -0.9398)
			(stroke
				(width 0.1)
				(type default)
			)
			(layer "B.SilkS")
		)
		(fp_line
			(start 1.5748 -0.9398)
			(end 1.5748 0.9398)
			(stroke
				(width 0.1)
				(type default)
			)
			(layer "B.SilkS")
		)
		(fp_rect
			(start 1.5748 0.9398)
			(end -1.5748 -0.9398)
			(stroke
				(width 0)
				(type default)
			)
			(fill no)
			(layer "B.CrtYd")
		)
		(fp_line
			(start -1.016 0.635)
			(end -1.016 -0.635)
			(stroke
				(width 0.1)
				(type default)
			)
			(layer "B.Fab")
		)
		(fp_line
			(start 1.016 0.635)
			(end -1.016 0.635)
			(stroke
				(width 0.1)
				(type default)
			)
			(layer "B.Fab")
		)
		(fp_line
			(start -1.016 -0.635)
			(end 1.016 -0.635)
			(stroke
				(width 0.1)
				(type default)
			)
			(layer "B.Fab")
		)
		(fp_line
			(start 1.016 -0.635)
			(end 1.016 0.635)
			(stroke
				(width 0.1)
				(type default)
			)
			(layer "B.Fab")
		)
		(pad "1" smd rect
			(at 0.8382 0 90)
			(size 0.9652 1.3716)
			(layers "B.Cu" "B.Mask" "B.Paste")
			(net "XP5R0V_MAC")
		)
		(pad "2" smd rect
			(at -0.8382 0 90)
			(size 0.9652 1.3716)
			(layers "B.Cu" "B.Mask" "B.Paste")
			(net "SG")
		)
		(zone
			(layer "B.Cu")
			(hatch none 0.5)
			(connect_pads
				(clearance 0)
			)
			(min_thickness 0.25)
			(keepout
				(tracks allowed)
				(vias not_allowed)
				(pads allowed)
				(copperpour not_allowed)
				(footprints allowed)
			)
			(placement
				(enabled no)
				(sheetname "")
			)
			(fill
				(thermal_gap 0.5)
				(thermal_bridge_width 0.5)
				(island_removal_mode 0)
			)
			(polygon
				(pts
					(xy 74.549 -72.9234) (xy 75.819 -72.9234) (xy 75.819 -73.3806) (xy 74.549 -73.3806)
				)
			)
		)
	)
)
